#ISCELL
  pure_quanta quanta_title_block_c *
  *
#ISCELL
  logical_power universal_gnd *
  page41_i1
#CELL
  pure_quanta socket4677_azif0045p001c01cs *
  page41_i10
#CELL
  pure_quanta socket4677_azif0045p001c01cs *
  page41_i11
#ISCELL
  logical_power universal_gnd *
  page41_i3
#ISCELL
  logical_power universal_gnd *
  page41_i4
#ISCELL
  logical_power universal_gnd *
  page41_i5
#ISCELL
  logical_power universal_gnd *
  page41_i6
#ISCELL
  logical_power universal_gnd *
  page41_i8
#CELL
  pure_quanta socket4677_azif0045p001c01cs *
  page41_i9
